# S9S_MB_2U (Grand Teton) — schematic netlist excerpt (pin names and nets, part order shuffled) for the footprints in the layout excerpt that follows; sources: Cadence DE-HDL packaged netlist, KiCad conversion of 03242023_DA0F0TMBIJ0_F0T_Motherboard_J_brd_V01_OCP.brd

C2394  Q_CAP  0.1UF 25V 10% X7R  pkg 0402  page 306 : A = U206_VDD ; B = GND
PR1779  Q_RES  0 5% CHIP  pkg 0402LF  page 276 : A = PVCCFA_EHV_CPU0_NC1 ; B = PVCCFA_EHV_CPU0_VDD1

(kicad_pcb
	(version 20260206)
	(generator "pcbnew")
	(generator_version "10.0")
	(general
		(thickness 1.6)
		(legacy_teardrops no)
	)
	(paper "A4")
	(title_block
		(title "03242023_DA0F0TMBIJ0_F0T_Motherboard_J_brd_V01_OCP.brd")
		(comment 1 "Grand Teton / footprints 181-182 of 6105")
	)
	(layers
		(0 "F.Cu" signal "TOP")
		(4 "In1.Cu" signal "GND")
		(6 "In2.Cu" signal "IN1")
		(8 "In3.Cu" signal "GND1")
		(10 "In4.Cu" signal "IN2")
		(12 "In5.Cu" signal "GND2")
		(14 "In6.Cu" signal "IN3")
		(16 "In7.Cu" signal "GND3")
		(18 "In8.Cu" signal "VCC")
		(20 "In9.Cu" signal "VCC1")
		(22 "In10.Cu" signal "GND4")
		(24 "In11.Cu" signal "IN4")
		(26 "In12.Cu" signal "GND5")
		(28 "In13.Cu" signal "IN5")
		(30 "In14.Cu" signal "GND6")
		(32 "In15.Cu" signal "IN6")
		(34 "In16.Cu" signal "GND7")
		(2 "B.Cu" signal "BOTTOM")
		(9 "F.Adhes" user "F.Adhesive")
		(11 "B.Adhes" user "B.Adhesive")
		(13 "F.Paste" user "Package Geometry/Pastemask Top")
		(15 "B.Paste" user "Package Geometry/Pastemask Bottom")
		(5 "F.SilkS" user "Ref Des/Silkscreen Top")
		(7 "B.SilkS" user "Ref Des/Silkscreen Bottom")
		(1 "F.Mask" user "Board Geometry/Soldermask Top")
		(3 "B.Mask" user "Board Geometry/Soldermask Bottom")
		(17 "Dwgs.User" user "User.Drawings")
		(19 "Cmts.User" user "User.Comments")
		(21 "Eco1.User" user "User.Eco1")
		(23 "Eco2.User" user "User.Eco2")
		(25 "Edge.Cuts" user "Board Geometry/Outline")
		(27 "Margin" user)
		(31 "F.CrtYd" user "Package Geometry/Place Bound Top")
		(29 "B.CrtYd" user "Package Geometry/Place Bound Bottom")
		(35 "F.Fab" user "Ref Des/Assembly Top")
		(33 "B.Fab" user "Ref Des/Assembly Bottom")
	)
	(footprint ""
		(layer "F.Cu")
		(at 220.087444 -99.21748)
		(property "Reference" "C2394"
			(at 0 0 0)
			(layer "F.SilkS")
			(hide yes)
			(effects
				(font
					(size 1.27 1.27)
				)
			)
		)
		(property "Value" ""
			(at 0 0 0)
			(layer "F.Fab")
			(effects
				(font
					(size 1.27 1.27)
				)
			)
		)
		(duplicate_pad_numbers_are_jumpers no)
		(fp_line
			(start -0.7874 -0.4064)
			(end 0.7874 -0.4064)
			(stroke
				(width 0.1524)
				(type default)
			)
			(layer "F.SilkS")
		)
		(fp_line
			(start -0.7874 0.4064)
			(end -0.7874 -0.4064)
			(stroke
				(width 0.1524)
				(type default)
			)
			(layer "F.SilkS")
		)
		(fp_line
			(start 0.7874 -0.4064)
			(end 0.7874 0.4064)
			(stroke
				(width 0.1524)
				(type default)
			)
			(layer "F.SilkS")
		)
		(fp_line
			(start 0.7874 0.4064)
			(end -0.7874 0.4064)
			(stroke
				(width 0.1524)
				(type default)
			)
			(layer "F.SilkS")
		)
		(fp_line
			(start -0.67945 -0.305054)
			(end -0.12065 -0.305054)
			(stroke
				(width 0.1)
				(type default)
			)
			(layer "F.Fab")
		)
		(fp_line
			(start -0.67945 0.3048)
			(end -0.67945 -0.305054)
			(stroke
				(width 0.1)
				(type default)
			)
			(layer "F.Fab")
		)
		(fp_line
			(start -0.12065 -0.305054)
			(end -0.12065 -0.2794)
			(stroke
				(width 0.1)
				(type default)
			)
			(layer "F.Fab")
		)
		(fp_line
			(start -0.12065 -0.2794)
			(end 0.12065 -0.2794)
			(stroke
				(width 0.1)
				(type default)
			)
			(layer "F.Fab")
		)
		(fp_line
			(start -0.12065 0.2794)
			(end -0.12065 0.3048)
			(stroke
				(width 0.1)
				(type default)
			)
			(layer "F.Fab")
		)
		(fp_line
			(start -0.12065 0.3048)
			(end -0.67945 0.3048)
			(stroke
				(width 0.1)
				(type default)
			)
			(layer "F.Fab")
		)
		(fp_line
			(start 0.120396 0.2794)
			(end -0.12065 0.2794)
			(stroke
				(width 0.1)
				(type default)
			)
			(layer "F.Fab")
		)
		(fp_line
			(start 0.120396 0.3048)
			(end 0.120396 0.2794)
			(stroke
				(width 0.1)
				(type default)
			)
			(layer "F.Fab")
		)
		(fp_line
			(start 0.12065 -0.3048)
			(end 0.67945 -0.3048)
			(stroke
				(width 0.1)
				(type default)
			)
			(layer "F.Fab")
		)
		(fp_line
			(start 0.12065 -0.2794)
			(end 0.12065 -0.3048)
			(stroke
				(width 0.1)
				(type default)
			)
			(layer "F.Fab")
		)
		(fp_line
			(start 0.67945 -0.3048)
			(end 0.67945 0.3048)
			(stroke
				(width 0.1)
				(type default)
			)
			(layer "F.Fab")
		)
		(fp_line
			(start 0.67945 0.3048)
			(end 0.120396 0.3048)
			(stroke
				(width 0.1)
				(type default)
			)
			(layer "F.Fab")
		)
		(pad "1" smd circle
			(at -0.40005 0)
			(size 0 0)
			(layers "F.Cu" "F.Mask" "F.Paste")
			(net "U206_VDD")
		)
		(pad "2" smd circle
			(at 0.40005 0)
			(size 0 0)
			(layers "F.Cu" "F.Mask" "F.Paste")
			(net "GND")
		)
	)
	(footprint ""
		(layer "F.Cu")
		(at 419.91788 -156.632148 90)
		(property "Reference" "PR1779"
			(at 0 0 90)
			(layer "F.SilkS")
			(hide yes)
			(effects
				(font
					(size 1.27 1.27)
				)
			)
		)
		(property "Value" ""
			(at 0 0 90)
			(layer "F.Fab")
			(effects
				(font
					(size 1.27 1.27)
				)
			)
		)
		(duplicate_pad_numbers_are_jumpers no)
		(fp_line
			(start 0.7874 -0.4064)
			(end 0.7874 0.4064)
			(stroke
				(width 0.1524)
				(type default)
			)
			(layer "F.SilkS")
		)
		(fp_line
			(start -0.7874 -0.4064)
			(end 0.7874 -0.4064)
			(stroke
				(width 0.1524)
				(type default)
			)
			(layer "F.SilkS")
		)
		(fp_line
			(start 0.7874 0.4064)
			(end -0.7874 0.4064)
			(stroke
				(width 0.1524)
				(type default)
			)
			(layer "F.SilkS")
		)
		(fp_line
			(start -0.7874 0.4064)
			(end -0.7874 -0.4064)
			(stroke
				(width 0.1524)
				(type default)
			)
			(layer "F.SilkS")
		)
		(fp_line
			(start -0.12065 -0.305054)
			(end -0.12065 -0.2794)
			(stroke
				(width 0.1)
				(type default)
			)
			(layer "F.Fab")
		)
		(fp_line
			(start -0.67945 -0.305054)
			(end -0.12065 -0.305054)
			(stroke
				(width 0.1)
				(type default)
			)
			(layer "F.Fab")
		)
		(fp_line
			(start 0.67945 -0.3048)
			(end 0.67945 0.3048)
			(stroke
				(width 0.1)
				(type default)
			)
			(layer "F.Fab")
		)
		(fp_line
			(start 0.12065 -0.3048)
			(end 0.67945 -0.3048)
			(stroke
				(width 0.1)
				(type default)
			)
			(layer "F.Fab")
		)
		(fp_line
			(start 0.12065 -0.2794)
			(end 0.12065 -0.3048)
			(stroke
				(width 0.1)
				(type default)
			)
			(layer "F.Fab")
		)
		(fp_line
			(start -0.12065 -0.2794)
			(end 0.12065 -0.2794)
			(stroke
				(width 0.1)
				(type default)
			)
			(layer "F.Fab")
		)
		(fp_line
			(start 0.120396 0.2794)
			(end -0.12065 0.2794)
			(stroke
				(width 0.1)
				(type default)
			)
			(layer "F.Fab")
		)
		(fp_line
			(start -0.12065 0.2794)
			(end -0.12065 0.3048)
			(stroke
				(width 0.1)
				(type default)
			)
			(layer "F.Fab")
		)
		(fp_line
			(start 0.67945 0.3048)
			(end 0.120396 0.3048)
			(stroke
				(width 0.1)
				(type default)
			)
			(layer "F.Fab")
		)
		(fp_line
			(start 0.120396 0.3048)
			(end 0.120396 0.2794)
			(stroke
				(width 0.1)
				(type default)
			)
			(layer "F.Fab")
		)
		(fp_line
			(start -0.12065 0.3048)
			(end -0.67945 0.3048)
			(stroke
				(width 0.1)
				(type default)
			)
			(layer "F.Fab")
		)
		(fp_line
			(start -0.67945 0.3048)
			(end -0.67945 -0.305054)
			(stroke
				(width 0.1)
				(type default)
			)
			(layer "F.Fab")
		)
		(pad "1" smd circle
			(at -0.40005 0 90)
			(size 0 0)
			(layers "F.Cu" "F.Mask" "F.Paste")
			(net "PVCCFA_EHV_CPU0_NC1")
		)
		(pad "2" smd circle
			(at 0.40005 0 90)
			(size 0 0)
			(layers "F.Cu" "F.Mask" "F.Paste")
			(net "PVCCFA_EHV_CPU0_VDD1")
		)
	)
)
